(kicad_pcb
	(version 20241229)
	(generator "pcbnew")
	(generator_version "9.0")
	(general
		(thickness 1.6)
		(legacy_teardrops no)
	)
	(paper "A4")
	(title_block
		(title "environment-sensor")
		(comment 1 "footprints 87-92 of 109")
	)
	(layers
		(0 "F.Cu" signal)
		(4 "In1.Cu" signal)
		(6 "In2.Cu" signal)
		(2 "B.Cu" signal)
		(9 "F.Adhes" user "F.Adhesive")
		(11 "B.Adhes" user "B.Adhesive")
		(13 "F.Paste" user)
		(15 "B.Paste" user)
		(5 "F.SilkS" user "F.Silkscreen")
		(7 "B.SilkS" user "B.Silkscreen")
		(1 "F.Mask" user)
		(3 "B.Mask" user)
		(17 "Dwgs.User" user "User.Drawings")
		(19 "Cmts.User" user "User.Comments")
		(21 "Eco1.User" user "User.Eco1")
		(23 "Eco2.User" user "User.Eco2")
		(25 "Edge.Cuts" user)
		(27 "Margin" user)
		(31 "F.CrtYd" user "F.Courtyard")
		(29 "B.CrtYd" user "B.Courtyard")
		(35 "F.Fab" user)
		(33 "B.Fab" user)
	)
	(footprint "antmicro-footprints:R_0402_1005Metric"
		(layer "F.Cu")
		(at 189.344 125.087 90)
		(descr "Resistor SMD 0402")
		(tags "resistor SMD 0402")
		(property "Reference" "R28"
			(at 4.887 5.756 180)
			(layer "F.SilkS")
			(effects
				(font
					(size 0.7 0.7)
					(thickness 0.15)
				)
				(justify left bottom)
			)
		)
		(property "Value" "R_100R_0402"
			(at 0 1.4 90)
			(layer "F.Fab")
			(effects
				(font
					(size 0.7 0.7)
					(thickness 0.15)
				)
				(justify left bottom)
			)
		)
		(property "Description" "SMD Chip Resistor, 100 ohm, ± 1%, 62.5 mW, 0402 [1005 Metric], Thick Film, General Purpose"
			(at 0 0 90)
			(layer "F.Fab")
			(hide yes)
			(effects
				(font
					(size 1.27 1.27)
					(thickness 0.15)
				)
			)
		)
		(property "Author" "Antmicro"
			(at 314.431 -64.257 0)
			(layer "F.Fab")
			(hide yes)
			(effects
				(font
					(size 1 1)
					(thickness 0.15)
				)
			)
		)
		(property "License" "Apache-2.0"
			(at 314.431 -64.257 0)
			(layer "F.Fab")
			(hide yes)
			(effects
				(font
					(size 1 1)
					(thickness 0.15)
				)
			)
		)
		(property "MPN" "CR0402-FX-1000GLF"
			(at 314.431 -64.257 0)
			(layer "F.Fab")
			(hide yes)
			(effects
				(font
					(size 1 1)
					(thickness 0.15)
				)
			)
		)
		(property "Manufacturer" "Bourns"
			(at 314.431 -64.257 0)
			(layer "F.Fab")
			(hide yes)
			(effects
				(font
					(size 1 1)
					(thickness 0.15)
				)
			)
		)
		(property "Public" "False"
			(at 314.431 -64.257 0)
			(layer "F.Fab")
			(hide yes)
			(effects
				(font
					(size 1 1)
					(thickness 0.15)
				)
			)
		)
		(property "Tolerance" "1%"
			(at 314.431 -64.257 0)
			(layer "F.Fab")
			(hide yes)
			(effects
				(font
					(size 1 1)
					(thickness 0.15)
				)
			)
		)
		(property "Val" "100R"
			(at 314.431 -64.257 0)
			(layer "F.Fab")
			(hide yes)
			(effects
				(font
					(size 1 1)
					(thickness 0.15)
				)
			)
		)
		(sheetfile "environment-sensor.kicad_sch")
		(attr smd)
		(fp_rect
			(start -0.925 -0.47)
			(end 0.925 0.47)
			(stroke
				(width 0.05)
				(type default)
			)
			(fill no)
			(layer "F.CrtYd")
		)
		(fp_rect
			(start -0.5 -0.25)
			(end 0.5 0.25)
			(stroke
				(width 0.15)
				(type solid)
			)
			(fill no)
			(layer "F.Fab")
		)
		(pad "1" smd roundrect
			(at -0.48 0 90)
			(size 0.59 0.64)
			(layers "F.Cu" "F.Mask" "F.Paste")
			(roundrect_rratio 0.25)
			(net 50 "Net-(U3-PB9)")
			(pintype "passive")
		)
		(pad "2" smd roundrect
			(at 0.48 0 90)
			(size 0.59 0.64)
			(layers "F.Cu" "F.Mask" "F.Paste")
			(roundrect_rratio 0.25)
			(net 9 "I2C_1_SDA")
			(pintype "passive")
		)
	)
	(footprint "antmicro-footprints:C_0402_1005Metric"
		(layer "F.Cu")
		(at 169.55 137.3 180)
		(descr "Capacitor SMD 0402")
		(tags "capacitor SMD 0402")
		(property "Reference" "C4"
			(at 0.982 -0.252 180)
			(layer "F.SilkS")
			(effects
				(font
					(size 0.7 0.7)
					(thickness 0.15)
				)
				(justify right bottom)
			)
		)
		(property "Value" "C_2u2_0402"
			(at 0 1.4 0)
			(layer "F.Fab")
			(effects
				(font
					(size 0.7 0.7)
					(thickness 0.15)
				)
				(justify right bottom)
			)
		)
		(property "Description" "SMD Multilayer Ceramic Capacitor, 2.2 µF, 10 V, 0402 [1005 Metric], ± 10%, X5R, C"
			(at 0 0 180)
			(layer "F.Fab")
			(hide yes)
			(effects
				(font
					(size 1.27 1.27)
					(thickness 0.15)
				)
			)
		)
		(property "Author" "Antmicro"
			(at 339.1 274.6 0)
			(layer "F.Fab")
			(hide yes)
			(effects
				(font
					(size 1 1)
					(thickness 0.15)
				)
			)
		)
		(property "Dielectric" ""
			(at 339.1 274.6 0)
			(layer "F.Fab")
			(hide yes)
			(effects
				(font
					(size 1 1)
					(thickness 0.15)
				)
			)
		)
		(property "License" "Apache-2.0"
			(at 339.1 274.6 0)
			(layer "F.Fab")
			(hide yes)
			(effects
				(font
					(size 1 1)
					(thickness 0.15)
				)
			)
		)
		(property "MPN" "C1005X5R1A225K050BC"
			(at 339.1 274.6 0)
			(layer "F.Fab")
			(hide yes)
			(effects
				(font
					(size 1 1)
					(thickness 0.15)
				)
			)
		)
		(property "Manufacturer" "TDK"
			(at 339.1 274.6 0)
			(layer "F.Fab")
			(hide yes)
			(effects
				(font
					(size 1 1)
					(thickness 0.15)
				)
			)
		)
		(property "Public" "False"
			(at 339.1 274.6 0)
			(layer "F.Fab")
			(hide yes)
			(effects
				(font
					(size 1 1)
					(thickness 0.15)
				)
			)
		)
		(property "Val" "2u2"
			(at 339.1 274.6 0)
			(layer "F.Fab")
			(hide yes)
			(effects
				(font
					(size 1 1)
					(thickness 0.15)
				)
			)
		)
		(property "Voltage" ""
			(at 339.1 274.6 0)
			(layer "F.Fab")
			(hide yes)
			(effects
				(font
					(size 1 1)
					(thickness 0.15)
				)
			)
		)
		(sheetfile "environment-sensor.kicad_sch")
		(attr smd)
		(fp_rect
			(start -0.925 -0.47)
			(end 0.925 0.47)
			(stroke
				(width 0.05)
				(type default)
			)
			(fill no)
			(layer "F.CrtYd")
		)
		(fp_line
			(start 0.504 0.248)
			(end -0.494 0.248)
			(stroke
				(width 0.15)
				(type solid)
			)
			(layer "F.Fab")
		)
		(fp_line
			(start 0.504 -0.25)
			(end 0.504 0.248)
			(stroke
				(width 0.15)
				(type solid)
			)
			(layer "F.Fab")
		)
		(fp_line
			(start -0.494 0.248)
			(end -0.494 -0.25)
			(stroke
				(width 0.15)
				(type solid)
			)
			(layer "F.Fab")
		)
		(fp_line
			(start -0.494 -0.25)
			(end 0.504 -0.25)
			(stroke
				(width 0.15)
				(type solid)
			)
			(layer "F.Fab")
		)
		(pad "1" smd roundrect
			(at -0.48 0 180)
			(size 0.59 0.64)
			(layers "F.Cu" "F.Mask" "F.Paste")
			(roundrect_rratio 0.25)
			(net 1 "GND")
			(pintype "passive")
		)
		(pad "2" smd roundrect
			(at 0.48 0 180)
			(size 0.59 0.64)
			(layers "F.Cu" "F.Mask" "F.Paste")
			(roundrect_rratio 0.25)
			(net 27 "/VBUS")
			(pintype "passive")
		)
	)
	(footprint "antmicro-footprints:R_0402_1005Metric"
		(layer "F.Cu")
		(at 177.5 126.25 90)
		(descr "Resistor SMD 0402")
		(tags "resistor SMD 0402")
		(property "Reference" "R8"
			(at 11.75 1.773 270)
			(layer "B.SilkS")
			(effects
				(font
					(size 0.7 0.7)
					(thickness 0.15)
				)
				(justify left bottom mirror)
			)
		)
		(property "Value" "R_0R_0402"
			(at 0 1.4 90)
			(layer "F.Fab")
			(effects
				(font
					(size 0.7 0.7)
					(thickness 0.15)
				)
				(justify left bottom)
			)
		)
		(property "Description" "SMD Chip Resistor, Jumper, 0 ohm, 100 mW, 0402 [1005 Metric], Thick Film, General Purpose"
			(at 0 0 90)
			(layer "F.Fab")
			(hide yes)
			(effects
				(font
					(size 1.27 1.27)
					(thickness 0.15)
				)
			)
		)
		(property "Author" "Antmicro"
			(at 303.75 -51.25 0)
			(layer "F.Fab")
			(hide yes)
			(effects
				(font
					(size 1 1)
					(thickness 0.15)
				)
			)
		)
		(property "Current" "1A"
			(at 303.75 -51.25 0)
			(layer "F.Fab")
			(hide yes)
			(effects
				(font
					(size 1 1)
					(thickness 0.15)
				)
			)
		)
		(property "License" "Apache-2.0"
			(at 303.75 -51.25 0)
			(layer "F.Fab")
			(hide yes)
			(effects
				(font
					(size 1 1)
					(thickness 0.15)
				)
			)
		)
		(property "MPN" "ERJ2GE0R00X"
			(at 303.75 -51.25 0)
			(layer "F.Fab")
			(hide yes)
			(effects
				(font
					(size 1 1)
					(thickness 0.15)
				)
			)
		)
		(property "Manufacturer" "Panasonic"
			(at 303.75 -51.25 0)
			(layer "F.Fab")
			(hide yes)
			(effects
				(font
					(size 1 1)
					(thickness 0.15)
				)
			)
		)
		(property "Public" "False"
			(at 303.75 -51.25 0)
			(layer "F.Fab")
			(hide yes)
			(effects
				(font
					(size 1 1)
					(thickness 0.15)
				)
			)
		)
		(property "Tolerance" ""
			(at 303.75 -51.25 0)
			(layer "F.Fab")
			(hide yes)
			(effects
				(font
					(size 1 1)
					(thickness 0.15)
				)
			)
		)
		(property "Val" "0R"
			(at 303.75 -51.25 0)
			(layer "F.Fab")
			(hide yes)
			(effects
				(font
					(size 1 1)
					(thickness 0.15)
				)
			)
		)
		(sheetfile "environment-sensor.kicad_sch")
		(attr smd)
		(fp_rect
			(start -0.925 -0.47)
			(end 0.925 0.47)
			(stroke
				(width 0.05)
				(type default)
			)
			(fill no)
			(layer "F.CrtYd")
		)
		(fp_rect
			(start -0.5 -0.25)
			(end 0.5 0.25)
			(stroke
				(width 0.15)
				(type solid)
			)
			(fill no)
			(layer "F.Fab")
		)
		(pad "1" smd roundrect
			(at -0.48 0 90)
			(size 0.59 0.64)
			(layers "F.Cu" "F.Mask" "F.Paste")
			(roundrect_rratio 0.25)
			(net 40 "Net-(U1-DCD#)")
			(pintype "passive")
		)
		(pad "2" smd roundrect
			(at 0.48 0 90)
			(size 0.59 0.64)
			(layers "F.Cu" "F.Mask" "F.Paste")
			(roundrect_rratio 0.25)
			(net 14 "NRST")
			(pintype "passive")
		)
	)
	(footprint "antmicro-footprints:C_0402_1005Metric"
		(layer "F.Cu")
		(at 205.15 117.835 90)
		(descr "Capacitor SMD 0402")
		(tags "capacitor SMD 0402")
		(property "Reference" "C28"
			(at -3.465 -5.05 180)
			(layer "F.SilkS")
			(effects
				(font
					(size 0.7 0.7)
					(thickness 0.15)
				)
				(justify left bottom)
			)
		)
		(property "Value" "C_100n_0402"
			(at 0 1.4 90)
			(layer "F.Fab")
			(effects
				(font
					(size 0.7 0.7)
					(thickness 0.15)
				)
				(justify left bottom)
			)
		)
		(property "Description" "SMD Multilayer Ceramic Capacitor, 0.1 µF, 50 V, 0402 [1005 Metric], ± 10%, X5R, GRM Series"
			(at 0 0 90)
			(layer "F.Fab")
			(hide yes)
			(effects
				(font
					(size 1.27 1.27)
					(thickness 0.15)
				)
			)
		)
		(property "Author" "Antmicro"
			(at 322.985 -87.315 0)
			(layer "F.Fab")
			(hide yes)
			(effects
				(font
					(size 1 1)
					(thickness 0.15)
				)
			)
		)
		(property "Dielectric" "X5R"
			(at 322.985 -87.315 0)
			(layer "F.Fab")
			(hide yes)
			(effects
				(font
					(size 1 1)
					(thickness 0.15)
				)
			)
		)
		(property "License" "Apache-2.0"
			(at 322.985 -87.315 0)
			(layer "F.Fab")
			(hide yes)
			(effects
				(font
					(size 1 1)
					(thickness 0.15)
				)
			)
		)
		(property "MPN" "GRM155R61H104KE14D"
			(at 322.985 -87.315 0)
			(layer "F.Fab")
			(hide yes)
			(effects
				(font
					(size 1 1)
					(thickness 0.15)
				)
			)
		)
		(property "Manufacturer" "Murata"
			(at 322.985 -87.315 0)
			(layer "F.Fab")
			(hide yes)
			(effects
				(font
					(size 1 1)
					(thickness 0.15)
				)
			)
		)
		(property "Public" "False"
			(at 322.985 -87.315 0)
			(layer "F.Fab")
			(hide yes)
			(effects
				(font
					(size 1 1)
					(thickness 0.15)
				)
			)
		)
		(property "Val" "100n"
			(at 322.985 -87.315 0)
			(layer "F.Fab")
			(hide yes)
			(effects
				(font
					(size 1 1)
					(thickness 0.15)
				)
			)
		)
		(property "Voltage" "50V"
			(at 322.985 -87.315 0)
			(layer "F.Fab")
			(hide yes)
			(effects
				(font
					(size 1 1)
					(thickness 0.15)
				)
			)
		)
		(sheetfile "environment-sensor.kicad_sch")
		(attr smd)
		(fp_rect
			(start -0.925 -0.47)
			(end 0.925 0.47)
			(stroke
				(width 0.05)
				(type default)
			)
			(fill no)
			(layer "F.CrtYd")
		)
		(fp_line
			(start 0.504 -0.25)
			(end 0.504 0.248)
			(stroke
				(width 0.15)
				(type solid)
			)
			(layer "F.Fab")
		)
		(fp_line
			(start -0.494 -0.25)
			(end 0.504 -0.25)
			(stroke
				(width 0.15)
				(type solid)
			)
			(layer "F.Fab")
		)
		(fp_line
			(start 0.504 0.248)
			(end -0.494 0.248)
			(stroke
				(width 0.15)
				(type solid)
			)
			(layer "F.Fab")
		)
		(fp_line
			(start -0.494 0.248)
			(end -0.494 -0.25)
			(stroke
				(width 0.15)
				(type solid)
			)
			(layer "F.Fab")
		)
		(pad "1" smd roundrect
			(at -0.48 0 90)
			(size 0.59 0.64)
			(layers "F.Cu" "F.Mask" "F.Paste")
			(roundrect_rratio 0.25)
			(net 2 "+3V3")
			(pintype "passive")
		)
		(pad "2" smd roundrect
			(at 0.48 0 90)
			(size 0.59 0.64)
			(layers "F.Cu" "F.Mask" "F.Paste")
			(roundrect_rratio 0.25)
			(net 1 "GND")
			(pintype "passive")
		)
	)
	(footprint "antmicro-footprints:R_0402_1005Metric"
		(layer "F.Cu")
		(at 193.744 125.087 90)
		(descr "Resistor SMD 0402")
		(tags "resistor SMD 0402")
		(property "Reference" "R23"
			(at 0.937 1.356 180)
			(layer "F.SilkS")
			(effects
				(font
					(size 0.7 0.7)
					(thickness 0.15)
				)
				(justify left bottom)
			)
		)
		(property "Value" "R_100R_0402"
			(at -1.011843 1.772047 90)
			(layer "F.Fab")
			(effects
				(font
					(size 0.7 0.7)
					(thickness 0.15)
				)
				(justify left bottom)
			)
		)
		(property "Description" "SMD Chip Resistor, 100 ohm, ± 1%, 62.5 mW, 0402 [1005 Metric], Thick Film, General Purpose"
			(at 0 0 90)
			(layer "F.Fab")
			(hide yes)
			(effects
				(font
					(size 1.27 1.27)
					(thickness 0.15)
				)
			)
		)
		(property "Author" "Antmicro"
			(at 318.831 -68.657 0)
			(layer "F.Fab")
			(hide yes)
			(effects
				(font
					(size 1 1)
					(thickness 0.15)
				)
			)
		)
		(property "License" "Apache-2.0"
			(at 318.831 -68.657 0)
			(layer "F.Fab")
			(hide yes)
			(effects
				(font
					(size 1 1)
					(thickness 0.15)
				)
			)
		)
		(property "MPN" "CR0402-FX-1000GLF"
			(at 318.831 -68.657 0)
			(layer "F.Fab")
			(hide yes)
			(effects
				(font
					(size 1 1)
					(thickness 0.15)
				)
			)
		)
		(property "Manufacturer" "Bourns"
			(at 318.831 -68.657 0)
			(layer "F.Fab")
			(hide yes)
			(effects
				(font
					(size 1 1)
					(thickness 0.15)
				)
			)
		)
		(property "Public" "False"
			(at 318.831 -68.657 0)
			(layer "F.Fab")
			(hide yes)
			(effects
				(font
					(size 1 1)
					(thickness 0.15)
				)
			)
		)
		(property "Tolerance" "1%"
			(at 318.831 -68.657 0)
			(layer "F.Fab")
			(hide yes)
			(effects
				(font
					(size 1 1)
					(thickness 0.15)
				)
			)
		)
		(property "Val" "100R"
			(at 318.831 -68.657 0)
			(layer "F.Fab")
			(hide yes)
			(effects
				(font
					(size 1 1)
					(thickness 0.15)
				)
			)
		)
		(sheetfile "environment-sensor.kicad_sch")
		(attr smd exclude_from_pos_files exclude_from_bom dnp)
		(fp_rect
			(start -0.925 -0.47)
			(end 0.925 0.47)
			(stroke
				(width 0.05)
				(type default)
			)
			(fill no)
			(layer "F.CrtYd")
		)
		(fp_rect
			(start -0.5 -0.25)
			(end 0.5 0.25)
			(stroke
				(width 0.15)
				(type solid)
			)
			(fill no)
			(layer "F.Fab")
		)
		(pad "1" smd roundrect
			(at -0.48 0 90)
			(size 0.59 0.64)
			(layers "F.Cu" "F.Mask" "F.Paste")
			(roundrect_rratio 0.25)
			(net 46 "Net-(U3-PA15)")
			(pintype "passive")
		)
		(pad "2" smd roundrect
			(at 0.48 0 90)
			(size 0.59 0.64)
			(layers "F.Cu" "F.Mask" "F.Paste")
			(roundrect_rratio 0.25)
			(net 8 "I2C_1_SCL")
			(pintype "passive")
		)
	)
	(footprint "antmicro-footprints:R_0402_1005Metric"
		(layer "F.Cu")
		(at 182.736 119.5855)
		(descr "Resistor SMD 0402")
		(tags "resistor SMD 0402")
		(property "Reference" "R32"
			(at -3.136 0.4145 0)
			(layer "F.SilkS")
			(effects
				(font
					(size 0.7 0.7)
					(thickness 0.15)
				)
				(justify left bottom)
			)
		)
		(property "Value" "R_100k_0402"
			(at 0 1.4 0)
			(layer "F.Fab")
			(effects
				(font
					(size 0.7 0.7)
					(thickness 0.15)
				)
				(justify left bottom)
			)
		)
		(property "Description" "SMD Chip Resistor, 100 kohm, ± 1%, 62.5 mW, 0402 [1005 Metric], Thick Film, General Purpose"
			(at 0 0 0)
			(layer "F.Fab")
			(hide yes)
			(effects
				(font
					(size 1.27 1.27)
					(thickness 0.15)
				)
			)
		)
		(property "Author" "Antmicro"
			(at 0 0 0)
			(layer "F.Fab")
			(hide yes)
			(effects
				(font
					(size 1 1)
					(thickness 0.15)
				)
			)
		)
		(property "License" "Apache-2.0"
			(at 0 0 0)
			(layer "F.Fab")
			(hide yes)
			(effects
				(font
					(size 1 1)
					(thickness 0.15)
				)
			)
		)
		(property "MPN" "CR0402-FX-1003GLF"
			(at 0 0 0)
			(layer "F.Fab")
			(hide yes)
			(effects
				(font
					(size 1 1)
					(thickness 0.15)
				)
			)
		)
		(property "Manufacturer" "Bourns"
			(at 0 0 0)
			(layer "F.Fab")
			(hide yes)
			(effects
				(font
					(size 1 1)
					(thickness 0.15)
				)
			)
		)
		(property "Public" "False"
			(at 0 0 0)
			(layer "F.Fab")
			(hide yes)
			(effects
				(font
					(size 1 1)
					(thickness 0.15)
				)
			)
		)
		(property "Tolerance" "1%"
			(at 0 0 0)
			(layer "F.Fab")
			(hide yes)
			(effects
				(font
					(size 1 1)
					(thickness 0.15)
				)
			)
		)
		(property "Val" "100k"
			(at 0 0 0)
			(layer "F.Fab")
			(hide yes)
			(effects
				(font
					(size 1 1)
					(thickness 0.15)
				)
			)
		)
		(sheetfile "environment-sensor.kicad_sch")
		(attr smd)
		(fp_rect
			(start -0.925 -0.47)
			(end 0.925 0.47)
			(stroke
				(width 0.05)
				(type default)
			)
			(fill no)
			(layer "F.CrtYd")
		)
		(fp_rect
			(start -0.5 -0.25)
			(end 0.5 0.25)
			(stroke
				(width 0.15)
				(type solid)
			)
			(fill no)
			(layer "F.Fab")
		)
		(pad "1" smd roundrect
			(at -0.48 0)
			(size 0.59 0.64)
			(layers "F.Cu" "F.Mask" "F.Paste")
			(roundrect_rratio 0.25)
			(net 1 "GND")
			(pintype "passive")
		)
		(pad "2" smd roundrect
			(at 0.48 0)
			(size 0.59 0.64)
			(layers "F.Cu" "F.Mask" "F.Paste")
			(roundrect_rratio 0.25)
			(net 51 "Net-(U4-A1)")
			(pintype "passive")
		)
	)
)
